(kicad_pcb
	(version 20260206)
	(generator "pcbnew")
	(generator_version "10.0")
	(general
		(thickness 1.6)
		(legacy_teardrops no)
	)
	(paper "A4")
	(title_block
		(title "baseboard — 13948-1b.1110WZS1818.brd")
		(comment 1 "Honey Badger (Wiwynn) / footprints 647-652 of 2523")
	)
	(layers
		(0 "F.Cu" signal "TOP")
		(4 "In1.Cu" signal "L2GND")
		(6 "In2.Cu" signal "L3")
		(8 "In3.Cu" signal "L4VCC")
		(10 "In4.Cu" signal "L5VCC")
		(12 "In5.Cu" signal "L6")
		(14 "In6.Cu" signal "L7GND")
		(2 "B.Cu" signal "BOTTOM")
		(9 "F.Adhes" user "F.Adhesive")
		(11 "B.Adhes" user "B.Adhesive")
		(13 "F.Paste" user "Package Geometry/Pastemask Top")
		(15 "B.Paste" user "Package Geometry/Pastemask Bottom")
		(5 "F.SilkS" user "Ref Des/Silkscreen Top")
		(7 "B.SilkS" user "Ref Des/Silkscreen Bottom")
		(1 "F.Mask" user "Board Geometry/Soldermask Top")
		(3 "B.Mask" user "Board Geometry/Soldermask Bottom")
		(17 "Dwgs.User" user "User.Drawings")
		(19 "Cmts.User" user "User.Comments")
		(21 "Eco1.User" user "User.Eco1")
		(23 "Eco2.User" user "User.Eco2")
		(25 "Edge.Cuts" user "Board Geometry/Outline")
		(27 "Margin" user)
		(31 "F.CrtYd" user "Package Geometry/Place Bound Top")
		(29 "B.CrtYd" user "Package Geometry/Place Bound Bottom")
		(35 "F.Fab" user "Ref Des/Assembly Top")
		(33 "B.Fab" user "Ref Des/Assembly Bottom")
	)
	(footprint ""
		(layer "F.Cu")
		(at 243.095272 -118.1735 180)
		(property "Reference" "SR936"
			(at 0 0 180)
			(layer "F.SilkS")
			(hide yes)
			(effects
				(font
					(size 1.27 1.27)
				)
			)
		)
		(property "Value" "0R2J-2-GP"
			(at 0.064008 -3.993896 180)
			(unlocked yes)
			(layer "F.Fab")
			(hide yes)
			(effects
				(font
					(size 1.016 1.016)
					(thickness 0.1524)
				)
			)
		)
		(property "Device Type" "R402H16"
			(at 0.064008 -5.517896 180)
			(unlocked yes)
			(layer "F.Fab")
			(hide yes)
			(effects
				(font
					(size 1.016 1.016)
					(thickness 0.1524)
				)
			)
		)
		(duplicate_pad_numbers_are_jumpers no)
		(fp_line
			(start 0.508 -0.9398)
			(end -0.508 -0.9398)
			(stroke
				(width 0.1524)
				(type default)
			)
			(layer "F.SilkS")
		)
		(fp_line
			(start -0.508 -0.9398)
			(end -0.508 0.9398)
			(stroke
				(width 0.1524)
				(type default)
			)
			(layer "F.SilkS")
		)
		(fp_rect
			(start -0.508 0.9398)
			(end 0.508 -0.9398)
			(stroke
				(width 0)
				(type default)
			)
			(fill no)
			(layer "F.CrtYd")
		)
		(fp_rect
			(start -0.508 0.9398)
			(end 0.508 -0.9398)
			(stroke
				(width 0)
				(type default)
			)
			(fill no)
			(layer "F.Fab")
		)
		(pad "1" smd custom
			(at 0 -0.4445 180)
			(size 0.1397 0.1397)
			(layers "F.Cu" "F.Mask" "F.Paste")
			(net "SAS_SMART_R_RX")
			(options
				(clearance outline)
				(anchor circle)
			)
			(primitives
				(gr_poly
					(pts
						(arc
							(start -0.1778 -0.2794)
							(mid -0.249642 -0.249642)
							(end -0.2794 -0.1778)
						)
						(arc
							(start -0.2794 0.1778)
							(mid -0.249642 0.249642)
							(end -0.1778 0.2794)
						)
						(arc
							(start 0.1778 0.2794)
							(mid 0.249642 0.249642)
							(end 0.2794 0.1778)
						)
						(arc
							(start 0.2794 -0.1778)
							(mid 0.249642 -0.249642)
							(end 0.1778 -0.2794)
						)
					)
					(width 0)
					(fill yes)
				)
			)
		)
		(pad "2" smd custom
			(at 0 0.4445 180)
			(size 0.1397 0.1397)
			(layers "F.Cu" "F.Mask" "F.Paste")
			(net "SAS_SMART_RX")
			(options
				(clearance outline)
				(anchor circle)
			)
			(primitives
				(gr_poly
					(pts
						(arc
							(start -0.1778 -0.2794)
							(mid -0.249642 -0.249642)
							(end -0.2794 -0.1778)
						)
						(arc
							(start -0.2794 0.1778)
							(mid -0.249642 0.249642)
							(end -0.1778 0.2794)
						)
						(arc
							(start 0.1778 0.2794)
							(mid 0.249642 0.249642)
							(end 0.2794 0.1778)
						)
						(arc
							(start 0.2794 -0.1778)
							(mid 0.249642 -0.249642)
							(end 0.1778 -0.2794)
						)
					)
					(width 0)
					(fill yes)
				)
			)
		)
	)
	(footprint ""
		(layer "F.Cu")
		(at 111.26597 -114.3 180)
		(property "Reference" "SC1079"
			(at 0 0 180)
			(layer "F.SilkS")
			(hide yes)
			(effects
				(font
					(size 1.27 1.27)
				)
			)
		)
		(property "Value" "SCD01U10V1KX-GP"
			(at -2.8321 -1.7399 180)
			(unlocked yes)
			(layer "F.Fab")
			(hide yes)
			(effects
				(font
					(size 1.016 1.016)
					(thickness 0.1524)
				)
			)
		)
		(property "Device Type" "C0201H13"
			(at -2.8321 -3.2639 180)
			(unlocked yes)
			(layer "F.Fab")
			(hide yes)
			(effects
				(font
					(size 1.016 1.016)
					(thickness 0.1524)
				)
			)
		)
		(duplicate_pad_numbers_are_jumpers no)
		(fp_rect
			(start -0.2794 0.6477)
			(end 0.2794 -0.6477)
			(stroke
				(width 0)
				(type default)
			)
			(fill no)
			(layer "F.CrtYd")
		)
		(fp_rect
			(start -0.2794 0.6477)
			(end 0.2794 -0.6477)
			(stroke
				(width 0)
				(type default)
			)
			(fill no)
			(layer "F.Fab")
		)
		(pad "1" smd custom
			(at 0 -0.2794 180)
			(size 0.0762 0.0762)
			(layers "F.Cu" "F.Mask" "F.Paste")
			(net "SAS_HDD_TX6_P")
			(options
				(clearance outline)
				(anchor circle)
			)
			(primitives
				(gr_poly
					(pts
						(arc
							(start 0.1524 -0.127)
							(mid 0.137521 -0.162921)
							(end 0.1016 -0.1778)
						)
						(arc
							(start -0.1016 -0.1778)
							(mid -0.137521 -0.162921)
							(end -0.1524 -0.127)
						)
						(arc
							(start -0.1524 0.127)
							(mid -0.137521 0.162921)
							(end -0.1016 0.1778)
						)
						(arc
							(start 0.1016 0.1778)
							(mid 0.137521 0.162921)
							(end 0.1524 0.127)
						)
					)
					(width 0)
					(fill yes)
				)
			)
		)
		(pad "2" smd custom
			(at 0 0.2794 180)
			(size 0.0762 0.0762)
			(layers "F.Cu" "F.Mask" "F.Paste")
			(net "SAS_EXP_GF_TX_DP10")
			(options
				(clearance outline)
				(anchor circle)
			)
			(primitives
				(gr_poly
					(pts
						(arc
							(start 0.1524 -0.127)
							(mid 0.137521 -0.162921)
							(end 0.1016 -0.1778)
						)
						(arc
							(start -0.1016 -0.1778)
							(mid -0.137521 -0.162921)
							(end -0.1524 -0.127)
						)
						(arc
							(start -0.1524 0.127)
							(mid -0.137521 0.162921)
							(end -0.1016 0.1778)
						)
						(arc
							(start 0.1016 0.1778)
							(mid 0.137521 0.162921)
							(end 0.1524 0.127)
						)
					)
					(width 0)
					(fill yes)
				)
			)
		)
	)
	(footprint ""
		(layer "F.Cu")
		(at 21.358352 -219.520008)
		(property "Reference" "SU14"
			(at 0 0 0)
			(layer "F.SilkS")
			(hide yes)
			(effects
				(font
					(size 1.27 1.27)
				)
			)
		)
		(property "Value" "PCA9575PW2-GP"
			(at 0.635 -8.0772 0)
			(unlocked yes)
			(layer "F.Fab")
			(hide yes)
			(effects
				(font
					(size 1.016 1.016)
					(thickness 0.1524)
				)
			)
		)
		(property "Device Type" "TSOIC28H44"
			(at 0.635 -9.9822 0)
			(unlocked yes)
			(layer "F.Fab")
			(hide yes)
			(effects
				(font
					(size 1.016 1.016)
					(thickness 0.1524)
				)
			)
		)
		(duplicate_pad_numbers_are_jumpers no)
		(fp_line
			(start -5.3467 -1.3716)
			(end 4.4704 -1.3716)
			(stroke
				(width 0.1524)
				(type default)
			)
			(layer "F.SilkS")
		)
		(fp_line
			(start -5.3467 -0.50292)
			(end -5.3467 -0.50038)
			(stroke
				(width 0.1524)
				(type default)
			)
			(layer "F.SilkS")
		)
		(fp_line
			(start -5.3467 -0.50038)
			(end -4.84632 0)
			(stroke
				(width 0.1524)
				(type default)
			)
			(layer "F.SilkS")
		)
		(fp_line
			(start -5.3467 1.7907)
			(end -5.3467 4.572)
			(stroke
				(width 0.508)
				(type default)
			)
			(layer "F.SilkS")
		)
		(fp_line
			(start -5.3467 4.572)
			(end -5.3467 -1.3716)
			(stroke
				(width 0.1524)
				(type default)
			)
			(layer "F.SilkS")
		)
		(fp_line
			(start -4.84632 0)
			(end -4.84632 0.00254)
			(stroke
				(width 0.1524)
				(type default)
			)
			(layer "F.SilkS")
		)
		(fp_line
			(start -4.84632 0.00254)
			(end -5.3467 0.50292)
			(stroke
				(width 0.1524)
				(type default)
			)
			(layer "F.SilkS")
		)
		(fp_line
			(start 4.4704 -1.3716)
			(end 4.4704 1.3716)
			(stroke
				(width 0.1524)
				(type default)
			)
			(layer "F.SilkS")
		)
		(fp_line
			(start 4.4704 1.3716)
			(end -5.3467 1.3716)
			(stroke
				(width 0.1524)
				(type default)
			)
			(layer "F.SilkS")
		)
		(fp_poly
			(pts
				(xy -4.55549 -1.8288) (xy -4.55549 1.8288) (xy 4.55549 1.8288) (xy 4.55549 -1.8288)
			)
			(stroke
				(width 0)
				(type default)
			)
			(fill yes)
			(layer "F.SilkS")
		)
		(fp_poly
			(pts
				(xy -5.3594 -4.0767) (xy 5.3594 -4.0767) (xy 5.3594 4.0767) (xy -5.3594 4.0767)
			)
			(stroke
				(width 0)
				(type default)
			)
			(fill no)
			(layer "F.CrtYd")
		)
		(fp_poly
			(pts
				(xy -5.3594 -4.0767) (xy 5.3594 -4.0767) (xy 5.3594 4.0767) (xy -5.3594 4.0767)
			)
			(stroke
				(width 0)
				(type default)
			)
			(fill no)
			(layer "F.Fab")
		)
		(pad "1" smd rect
			(at -4.22529 2.80543)
			(size 0.3556 1.524)
			(layers "F.Cu" "F.Mask" "F.Paste")
			(net "IO_EXP_HDD_PWR_A0")
		)
		(pad "2" smd rect
			(at -3.57505 2.80543)
			(size 0.3556 1.524)
			(layers "F.Cu" "F.Mask" "F.Paste")
			(net "P1V8_E")
		)
		(pad "3" smd rect
			(at -2.92481 2.80543)
			(size 0.3556 1.524)
			(layers "F.Cu" "F.Mask" "F.Paste")
			(net "I2C_IO_EXP_RESET#_PWR")
		)
		(pad "4" smd rect
			(at -2.27457 2.80543)
			(size 0.3556 1.524)
			(layers "F.Cu" "F.Mask" "F.Paste")
			(net "SAS_HDD_PWR0")
		)
		(pad "5" smd rect
			(at -1.6256 2.80543)
			(size 0.3556 1.524)
			(layers "F.Cu" "F.Mask" "F.Paste")
			(net "SAS_HDD_PWR1")
		)
		(pad "6" smd rect
			(at -0.97536 2.80543)
			(size 0.3556 1.524)
			(layers "F.Cu" "F.Mask" "F.Paste")
			(net "SAS_HDD_PWR2")
		)
		(pad "7" smd rect
			(at -0.32512 2.80543)
			(size 0.3556 1.524)
			(layers "F.Cu" "F.Mask" "F.Paste")
			(net "SAS_HDD_PWR3")
		)
		(pad "8" smd rect
			(at 0.32512 2.80543)
			(size 0.3556 1.524)
			(layers "F.Cu" "F.Mask" "F.Paste")
			(net "IO_EXP_HDD_PWR_A1")
		)
		(pad "9" smd rect
			(at 0.97536 2.80543)
			(size 0.3556 1.524)
			(layers "F.Cu" "F.Mask" "F.Paste")
			(net "P3V3_STBY")
		)
		(pad "10" smd rect
			(at 1.6256 2.80543)
			(size 0.3556 1.524)
			(layers "F.Cu" "F.Mask" "F.Paste")
			(net "SAS_HDD_PWR4")
		)
		(pad "11" smd rect
			(at 2.27457 2.80543)
			(size 0.3556 1.524)
			(layers "F.Cu" "F.Mask" "F.Paste")
			(net "SAS_HDD_PWR5")
		)
		(pad "12" smd rect
			(at 2.92481 2.80543)
			(size 0.3556 1.524)
			(layers "F.Cu" "F.Mask" "F.Paste")
			(net "SAS_HDD_PWR6")
		)
		(pad "13" smd rect
			(at 3.57505 2.80543)
			(size 0.3556 1.524)
			(layers "F.Cu" "F.Mask" "F.Paste")
			(net "SAS_HDD_PWR7")
		)
		(pad "14" smd rect
			(at 4.22529 2.80543)
			(size 0.3556 1.524)
			(layers "F.Cu" "F.Mask" "F.Paste")
			(net "HDD_PWR_IO_INT_N")
		)
		(pad "15" smd rect
			(at 4.22529 -2.80543)
			(size 0.3556 1.524)
			(layers "F.Cu" "F.Mask" "F.Paste")
			(net "IO_EXP_HDD_PWR_A2")
		)
		(pad "16" smd rect
			(at 3.57505 -2.80543)
			(size 0.3556 1.524)
			(layers "F.Cu" "F.Mask" "F.Paste")
			(net "GND")
		)
		(pad "17" smd rect
			(at 2.92481 -2.80543)
			(size 0.3556 1.524)
			(layers "F.Cu" "F.Mask" "F.Paste")
			(net "SAS_HDD_PWR15")
		)
		(pad "18" smd rect
			(at 2.27457 -2.80543)
			(size 0.3556 1.524)
			(layers "F.Cu" "F.Mask" "F.Paste")
			(net "SAS_HDD_PWR14")
		)
		(pad "19" smd rect
			(at 1.6256 -2.80543)
			(size 0.3556 1.524)
			(layers "F.Cu" "F.Mask" "F.Paste")
			(net "SAS_HDD_PWR13")
		)
		(pad "20" smd rect
			(at 0.97536 -2.80543)
			(size 0.3556 1.524)
			(layers "F.Cu" "F.Mask" "F.Paste")
			(net "SAS_HDD_PWR12")
		)
		(pad "21" smd rect
			(at 0.32512 -2.80543)
			(size 0.3556 1.524)
			(layers "F.Cu" "F.Mask" "F.Paste")
			(net "P3V3_STBY")
		)
		(pad "22" smd rect
			(at -0.32512 -2.80543)
			(size 0.3556 1.524)
			(layers "F.Cu" "F.Mask" "F.Paste")
			(net "IO_EXP_HDD_PWR_A3")
		)
		(pad "23" smd rect
			(at -0.97536 -2.80543)
			(size 0.3556 1.524)
			(layers "F.Cu" "F.Mask" "F.Paste")
			(net "SAS_HDD_PWR11")
		)
		(pad "24" smd rect
			(at -1.6256 -2.80543)
			(size 0.3556 1.524)
			(layers "F.Cu" "F.Mask" "F.Paste")
			(net "SAS_HDD_PWR10")
		)
		(pad "25" smd rect
			(at -2.27457 -2.80543)
			(size 0.3556 1.524)
			(layers "F.Cu" "F.Mask" "F.Paste")
			(net "SAS_HDD_PWR9")
		)
		(pad "26" smd rect
			(at -2.92481 -2.80543)
			(size 0.3556 1.524)
			(layers "F.Cu" "F.Mask" "F.Paste")
			(net "SAS_HDD_PWR8")
		)
		(pad "27" smd rect
			(at -3.57505 -2.80543)
			(size 0.3556 1.524)
			(layers "F.Cu" "F.Mask" "F.Paste")
			(net "PWR_SDA")
		)
		(pad "28" smd rect
			(at -4.22529 -2.80543)
			(size 0.3556 1.524)
			(layers "F.Cu" "F.Mask" "F.Paste")
			(net "PWR_SCL")
		)
	)
	(footprint ""
		(layer "F.Cu")
		(at 317.5 -110.617 90)
		(property "Reference" "PC31"
			(at 0 0 90)
			(layer "F.SilkS")
			(hide yes)
			(effects
				(font
					(size 1.27 1.27)
				)
			)
		)
		(property "Value" "SC1KP50V2KX-1GP"
			(at 1.1811 -2.7051 90)
			(unlocked yes)
			(layer "F.Fab")
			(hide yes)
			(effects
				(font
					(size 1.016 1.016)
					(thickness 0.1524)
				)
			)
		)
		(property "Device Type" "C402H22"
			(at 1.1811 -4.2291 90)
			(unlocked yes)
			(layer "F.Fab")
			(hide yes)
			(effects
				(font
					(size 1.016 1.016)
					(thickness 0.1524)
				)
			)
		)
		(duplicate_pad_numbers_are_jumpers no)
		(fp_rect
			(start -0.4318 0.9525)
			(end 0.4318 -0.9525)
			(stroke
				(width 0)
				(type default)
			)
			(fill no)
			(layer "F.CrtYd")
		)
		(fp_rect
			(start -0.4318 0.9525)
			(end 0.4318 -0.9525)
			(stroke
				(width 0)
				(type default)
			)
			(fill no)
			(layer "F.Fab")
		)
		(pad "1" smd custom
			(at 0 -0.4445 90)
			(size 0.1524 0.1524)
			(layers "F.Cu" "F.Mask" "F.Paste")
			(net "P3V3_STBY_LL_R")
			(options
				(clearance outline)
				(anchor circle)
			)
			(primitives
				(gr_poly
					(pts
						(arc
							(start 0.3048 -0.2032)
							(mid 0.275042 -0.275042)
							(end 0.2032 -0.3048)
						)
						(arc
							(start -0.2032 -0.3048)
							(mid -0.275042 -0.275042)
							(end -0.3048 -0.2032)
						)
						(arc
							(start -0.3048 0.2032)
							(mid -0.275042 0.275042)
							(end -0.2032 0.3048)
						)
						(arc
							(start 0.2032 0.3048)
							(mid 0.275042 0.275042)
							(end 0.3048 0.2032)
						)
					)
					(width 0)
					(fill yes)
				)
			)
		)
		(pad "2" smd custom
			(at 0 0.4445 90)
			(size 0.1524 0.1524)
			(layers "F.Cu" "F.Mask" "F.Paste")
			(net "P3V3_STBY_VFB")
			(options
				(clearance outline)
				(anchor circle)
			)
			(primitives
				(gr_poly
					(pts
						(arc
							(start 0.3048 -0.2032)
							(mid 0.275042 -0.275042)
							(end 0.2032 -0.3048)
						)
						(arc
							(start -0.2032 -0.3048)
							(mid -0.275042 -0.275042)
							(end -0.3048 -0.2032)
						)
						(arc
							(start -0.3048 0.2032)
							(mid -0.275042 0.275042)
							(end -0.2032 0.3048)
						)
						(arc
							(start 0.2032 0.3048)
							(mid 0.275042 0.275042)
							(end 0.3048 0.2032)
						)
					)
					(width 0)
					(fill yes)
				)
			)
		)
	)
	(footprint ""
		(layer "F.Cu")
		(at 84.455 -238.4044 180)
		(property "Reference" "SC432"
			(at 0 0 180)
			(layer "F.SilkS")
			(hide yes)
			(effects
				(font
					(size 1.27 1.27)
				)
			)
		)
		(property "Value" "SC1U10V3KX-4GP-U"
			(at 0 -2.8194 180)
			(unlocked yes)
			(layer "F.Fab")
			(hide yes)
			(effects
				(font
					(size 1.016 1.016)
					(thickness 0.1524)
				)
			)
		)
		(property "Device Type" "C603H36"
			(at 0 -4.3434 180)
			(unlocked yes)
			(layer "F.Fab")
			(hide yes)
			(effects
				(font
					(size 1.016 1.016)
					(thickness 0.1524)
				)
			)
		)
		(duplicate_pad_numbers_are_jumpers no)
		(fp_line
			(start 0.508 0)
			(end -0.508 0)
			(stroke
				(width 0.2032)
				(type default)
			)
			(layer "F.SilkS")
		)
		(fp_rect
			(start -0.5842 1.3335)
			(end 0.5842 -1.3335)
			(stroke
				(width 0)
				(type default)
			)
			(fill no)
			(layer "F.CrtYd")
		)
		(fp_rect
			(start -0.5842 1.3335)
			(end 0.5842 -1.3335)
			(stroke
				(width 0)
				(type default)
			)
			(fill no)
			(layer "F.Fab")
		)
		(pad "1" smd custom
			(at 0 -0.762 180)
			(size 0.2159 0.2159)
			(layers "F.Cu" "F.Mask" "F.Paste")
			(net "GND")
			(options
				(clearance outline)
				(anchor circle)
			)
			(primitives
				(gr_poly
					(pts
						(arc
							(start -0.3302 -0.4318)
							(mid -0.402042 -0.402042)
							(end -0.4318 -0.3302)
						)
						(arc
							(start -0.4318 0.3302)
							(mid -0.402042 0.402042)
							(end -0.3302 0.4318)
						)
						(arc
							(start 0.3302 0.4318)
							(mid 0.402042 0.402042)
							(end 0.4318 0.3302)
						)
						(arc
							(start 0.4318 -0.3302)
							(mid 0.402042 -0.402042)
							(end 0.3302 -0.4318)
						)
					)
					(width 0)
					(fill yes)
				)
			)
		)
		(pad "2" smd custom
			(at 0 0.762 180)
			(size 0.2159 0.2159)
			(layers "F.Cu" "F.Mask" "F.Paste")
			(net "P3V3_STBY")
			(options
				(clearance outline)
				(anchor circle)
			)
			(primitives
				(gr_poly
					(pts
						(arc
							(start -0.3302 -0.4318)
							(mid -0.402042 -0.402042)
							(end -0.4318 -0.3302)
						)
						(arc
							(start -0.4318 0.3302)
							(mid -0.402042 0.402042)
							(end -0.3302 0.4318)
						)
						(arc
							(start 0.3302 0.4318)
							(mid 0.402042 0.402042)
							(end 0.4318 0.3302)
						)
						(arc
							(start 0.4318 -0.3302)
							(mid 0.402042 -0.402042)
							(end 0.3302 -0.4318)
						)
					)
					(width 0)
					(fill yes)
				)
			)
		)
	)
	(footprint ""
		(layer "F.Cu")
		(at 180.529992 -25.4)
		(property "Reference" "TP132"
			(at 0 0 0)
			(layer "F.SilkS")
			(hide yes)
			(effects
				(font
					(size 1.27 1.27)
				)
			)
		)
		(property "Value" "TPAD28"
			(at 0.0127 -1.8034 0)
			(unlocked yes)
			(layer "F.Fab")
			(hide yes)
			(effects
				(font
					(size 1.016 1.016)
					(thickness 0.1524)
				)
			)
		)
		(property "Device Type" "TPAD28"
			(at 0.0127 -3.3274 0)
			(unlocked yes)
			(layer "F.Fab")
			(hide yes)
			(effects
				(font
					(size 1.016 1.016)
					(thickness 0.1524)
				)
			)
		)
		(duplicate_pad_numbers_are_jumpers no)
		(fp_poly
			(pts
				(arc
					(start 0.3556 0)
					(mid -0.3556 0)
					(end 0.3556 0)
				)
			)
			(stroke
				(width 0)
				(type default)
			)
			(fill no)
			(layer "F.CrtYd")
		)
		(fp_poly
			(pts
				(arc
					(start 0.6096 0)
					(mid -0.6096 0)
					(end 0.6096 0)
				)
			)
			(stroke
				(width 0)
				(type default)
			)
			(fill no)
			(layer "F.Fab")
		)
		(pad "1" smd circle
			(at 0 0)
			(size 0.7112 0.7112)
			(layers "F.Cu" "F.Mask" "F.Paste")
			(net "NC_PHYSPLOED_N")
		)
	)
)
